# SCM (Grand Teton) — schematic netlist excerpt (pin names and nets, part order shuffled) for the footprints in the layout excerpt that follows; sources: Cadence DE-HDL packaged netlist, KiCad conversion of 12092022_DA0F0TMDCD0_F0T_Management_Board_D_brd_V3_OCP.brd

C96  Q_CAP  0.1UF 25V 10% X7R  pkg 0402  page 17 : A = PGPPA_BMC_AUX ; B = GND
R741  Q_RES  4.7K 1% CHIP  pkg 0402LF  page 30 : A = P3V3_AUX ; B = UART_BMC_5_RXD_BUF

(kicad_pcb
	(version 20260206)
	(generator "pcbnew")
	(generator_version "10.0")
	(general
		(thickness 1.6)
		(legacy_teardrops no)
	)
	(paper "A4")
	(title_block
		(title "12092022_DA0F0TMDCD0_F0T_Management_Board_D_brd_V3_OCP.brd")
		(comment 1 "Grand Teton / footprints 1285-1286 of 1440")
	)
	(layers
		(0 "F.Cu" signal "TOP")
		(4 "In1.Cu" signal "GND")
		(6 "In2.Cu" signal "IN1")
		(8 "In3.Cu" signal "GND1")
		(10 "In4.Cu" signal "IN2")
		(12 "In5.Cu" signal "VCC")
		(14 "In6.Cu" signal "VCC1")
		(16 "In7.Cu" signal "IN3")
		(18 "In8.Cu" signal "GND2")
		(20 "In9.Cu" signal "IN4")
		(22 "In10.Cu" signal "GND3")
		(2 "B.Cu" signal "BOTTOM")
		(9 "F.Adhes" user "F.Adhesive")
		(11 "B.Adhes" user "B.Adhesive")
		(13 "F.Paste" user "Package Geometry/Pastemask Top")
		(15 "B.Paste" user "Package Geometry/Pastemask Bottom")
		(5 "F.SilkS" user "Ref Des/Silkscreen Top")
		(7 "B.SilkS" user "Ref Des/Silkscreen Bottom")
		(1 "F.Mask" user "Board Geometry/Soldermask Top")
		(3 "B.Mask" user "Board Geometry/Soldermask Bottom")
		(17 "Dwgs.User" user "User.Drawings")
		(19 "Cmts.User" user "User.Comments")
		(21 "Eco1.User" user "User.Eco1")
		(23 "Eco2.User" user "User.Eco2")
		(25 "Edge.Cuts" user "Board Geometry/Outline")
		(27 "Margin" user)
		(31 "F.CrtYd" user "Package Geometry/Place Bound Top")
		(29 "B.CrtYd" user "Package Geometry/Place Bound Bottom")
		(35 "F.Fab" user "Ref Des/Assembly Top")
		(33 "B.Fab" user "Ref Des/Assembly Bottom")
	)
	(footprint ""
		(layer "B.Cu")
		(at 53.424582 -55.13197 -90)
		(property "Reference" "C96"
			(at 0 0 90)
			(layer "B.SilkS")
			(hide yes)
			(effects
				(font
					(size 1.27 1.27)
				)
				(justify mirror)
			)
		)
		(property "Value" ""
			(at 0 0 90)
			(layer "B.Fab")
			(effects
				(font
					(size 1.27 1.27)
				)
				(justify mirror)
			)
		)
		(duplicate_pad_numbers_are_jumpers no)
		(fp_line
			(start -0.7874 0.4064)
			(end 0.7874 0.4064)
			(stroke
				(width 0.1524)
				(type default)
			)
			(layer "B.SilkS")
		)
		(fp_line
			(start 0.7874 0.4064)
			(end 0.7874 -0.4064)
			(stroke
				(width 0.1524)
				(type default)
			)
			(layer "B.SilkS")
		)
		(fp_line
			(start -0.7874 -0.4064)
			(end -0.7874 0.4064)
			(stroke
				(width 0.1524)
				(type default)
			)
			(layer "B.SilkS")
		)
		(fp_line
			(start 0.7874 -0.4064)
			(end -0.7874 -0.4064)
			(stroke
				(width 0.1524)
				(type default)
			)
			(layer "B.SilkS")
		)
		(fp_line
			(start -0.67945 0.3048)
			(end -0.120396 0.3048)
			(stroke
				(width 0.1)
				(type default)
			)
			(layer "B.Fab")
		)
		(fp_line
			(start -0.120396 0.3048)
			(end -0.120396 0.2794)
			(stroke
				(width 0.1)
				(type default)
			)
			(layer "B.Fab")
		)
		(fp_line
			(start 0.12065 0.3048)
			(end 0.67945 0.3048)
			(stroke
				(width 0.1)
				(type default)
			)
			(layer "B.Fab")
		)
		(fp_line
			(start 0.67945 0.3048)
			(end 0.67945 -0.305054)
			(stroke
				(width 0.1)
				(type default)
			)
			(layer "B.Fab")
		)
		(fp_line
			(start -0.120396 0.2794)
			(end 0.12065 0.2794)
			(stroke
				(width 0.1)
				(type default)
			)
			(layer "B.Fab")
		)
		(fp_line
			(start 0.12065 0.2794)
			(end 0.12065 0.3048)
			(stroke
				(width 0.1)
				(type default)
			)
			(layer "B.Fab")
		)
		(fp_line
			(start -0.12065 -0.2794)
			(end -0.12065 -0.3048)
			(stroke
				(width 0.1)
				(type default)
			)
			(layer "B.Fab")
		)
		(fp_line
			(start 0.12065 -0.2794)
			(end -0.12065 -0.2794)
			(stroke
				(width 0.1)
				(type default)
			)
			(layer "B.Fab")
		)
		(fp_line
			(start -0.67945 -0.3048)
			(end -0.67945 0.3048)
			(stroke
				(width 0.1)
				(type default)
			)
			(layer "B.Fab")
		)
		(fp_line
			(start -0.12065 -0.3048)
			(end -0.67945 -0.3048)
			(stroke
				(width 0.1)
				(type default)
			)
			(layer "B.Fab")
		)
		(fp_line
			(start 0.12065 -0.305054)
			(end 0.12065 -0.2794)
			(stroke
				(width 0.1)
				(type default)
			)
			(layer "B.Fab")
		)
		(fp_line
			(start 0.67945 -0.305054)
			(end 0.12065 -0.305054)
			(stroke
				(width 0.1)
				(type default)
			)
			(layer "B.Fab")
		)
		(pad "1" smd circle
			(at 0.40005 0 90)
			(size 0 0)
			(layers "B.Cu" "B.Mask" "B.Paste")
			(net "PGPPA_BMC_AUX")
		)
		(pad "2" smd circle
			(at -0.40005 0 90)
			(size 0 0)
			(layers "B.Cu" "B.Mask" "B.Paste")
			(net "GND")
		)
	)
	(footprint ""
		(layer "B.Cu")
		(at 11.9126 -26.9748)
		(property "Reference" "R741"
			(at 0 0 0)
			(layer "B.SilkS")
			(hide yes)
			(effects
				(font
					(size 1.27 1.27)
				)
				(justify mirror)
			)
		)
		(property "Value" ""
			(at 0 0 0)
			(layer "B.Fab")
			(effects
				(font
					(size 1.27 1.27)
				)
				(justify mirror)
			)
		)
		(duplicate_pad_numbers_are_jumpers no)
		(fp_line
			(start -0.7874 -0.4064)
			(end -0.7874 0.4064)
			(stroke
				(width 0.1524)
				(type default)
			)
			(layer "B.SilkS")
		)
		(fp_line
			(start -0.7874 0.4064)
			(end 0.7874 0.4064)
			(stroke
				(width 0.1524)
				(type default)
			)
			(layer "B.SilkS")
		)
		(fp_line
			(start 0.7874 -0.4064)
			(end -0.7874 -0.4064)
			(stroke
				(width 0.1524)
				(type default)
			)
			(layer "B.SilkS")
		)
		(fp_line
			(start 0.7874 0.4064)
			(end 0.7874 -0.4064)
			(stroke
				(width 0.1524)
				(type default)
			)
			(layer "B.SilkS")
		)
		(fp_line
			(start -0.67945 -0.3048)
			(end -0.67945 0.3048)
			(stroke
				(width 0.1)
				(type default)
			)
			(layer "B.Fab")
		)
		(fp_line
			(start -0.67945 0.3048)
			(end -0.120396 0.3048)
			(stroke
				(width 0.1)
				(type default)
			)
			(layer "B.Fab")
		)
		(fp_line
			(start -0.12065 -0.3048)
			(end -0.67945 -0.3048)
			(stroke
				(width 0.1)
				(type default)
			)
			(layer "B.Fab")
		)
		(fp_line
			(start -0.12065 -0.2794)
			(end -0.12065 -0.3048)
			(stroke
				(width 0.1)
				(type default)
			)
			(layer "B.Fab")
		)
		(fp_line
			(start -0.120396 0.2794)
			(end 0.12065 0.2794)
			(stroke
				(width 0.1)
				(type default)
			)
			(layer "B.Fab")
		)
		(fp_line
			(start -0.120396 0.3048)
			(end -0.120396 0.2794)
			(stroke
				(width 0.1)
				(type default)
			)
			(layer "B.Fab")
		)
		(fp_line
			(start 0.12065 -0.305054)
			(end 0.12065 -0.2794)
			(stroke
				(width 0.1)
				(type default)
			)
			(layer "B.Fab")
		)
		(fp_line
			(start 0.12065 -0.2794)
			(end -0.12065 -0.2794)
			(stroke
				(width 0.1)
				(type default)
			)
			(layer "B.Fab")
		)
		(fp_line
			(start 0.12065 0.2794)
			(end 0.12065 0.3048)
			(stroke
				(width 0.1)
				(type default)
			)
			(layer "B.Fab")
		)
		(fp_line
			(start 0.12065 0.3048)
			(end 0.67945 0.3048)
			(stroke
				(width 0.1)
				(type default)
			)
			(layer "B.Fab")
		)
		(fp_line
			(start 0.67945 -0.305054)
			(end 0.12065 -0.305054)
			(stroke
				(width 0.1)
				(type default)
			)
			(layer "B.Fab")
		)
		(fp_line
			(start 0.67945 0.3048)
			(end 0.67945 -0.305054)
			(stroke
				(width 0.1)
				(type default)
			)
			(layer "B.Fab")
		)
		(pad "1" smd circle
			(at 0.40005 0 180)
			(size 0 0)
			(layers "B.Cu" "B.Mask" "B.Paste")
			(net "P3V3_AUX")
		)
		(pad "2" smd circle
			(at -0.40005 0 180)
			(size 0 0)
			(layers "B.Cu" "B.Mask" "B.Paste")
			(net "UART_BMC_5_RXD_BUF")
		)
	)
)
